# T6G (Grand Teton) — schematic netlist excerpt (pin names and nets, part order shuffled) for the footprints in the layout excerpt that follows; sources: Cadence DE-HDL packaged netlist, KiCad conversion of 04192023_DAF0TMB3IC0_F0TG_MB_C_brd_V02_OCP.brd

C1063  Q_CAP  0.1UF 25V 10% X7R  pkg 0402  page 142 : A = P3V3_AUX ; B = GND
R4269  Q_RES  2.2K 5% EMPTY  pkg 0402LF  page 252 : A = P3V3_AUX ; B = SMB_VR_SENSOR_3V3AUX_SCL

(kicad_pcb
	(version 20260206)
	(generator "pcbnew")
	(generator_version "10.0")
	(general
		(thickness 1.6)
		(legacy_teardrops no)
	)
	(paper "A4")
	(title_block
		(title "04192023_DAF0TMB3IC0_F0TG_MB_C_brd_V02_OCP.brd")
		(comment 1 "Grand Teton / footprints 14-15 of 8354")
	)
	(layers
		(0 "F.Cu" signal "TOP")
		(4 "In1.Cu" signal "GND")
		(6 "In2.Cu" signal "IN1")
		(8 "In3.Cu" signal "GND1")
		(10 "In4.Cu" signal "IN2")
		(12 "In5.Cu" signal "GND2")
		(14 "In6.Cu" signal "IN3")
		(16 "In7.Cu" signal "GND3")
		(18 "In8.Cu" signal "VCC")
		(20 "In9.Cu" signal "VCC1")
		(22 "In10.Cu" signal "GND4")
		(24 "In11.Cu" signal "IN4")
		(26 "In12.Cu" signal "GND5")
		(28 "In13.Cu" signal "IN5")
		(30 "In14.Cu" signal "GND6")
		(32 "In15.Cu" signal "IN6")
		(34 "In16.Cu" signal "GND7")
		(2 "B.Cu" signal "BOTTOM")
		(9 "F.Adhes" user "F.Adhesive")
		(11 "B.Adhes" user "B.Adhesive")
		(13 "F.Paste" user "Package Geometry/Pastemask Top")
		(15 "B.Paste" user "Package Geometry/Pastemask Bottom")
		(5 "F.SilkS" user "Ref Des/Silkscreen Top")
		(7 "B.SilkS" user "Ref Des/Silkscreen Bottom")
		(1 "F.Mask" user "Board Geometry/Soldermask Top")
		(3 "B.Mask" user "Board Geometry/Soldermask Bottom")
		(17 "Dwgs.User" user "User.Drawings")
		(19 "Cmts.User" user "User.Comments")
		(21 "Eco1.User" user "User.Eco1")
		(23 "Eco2.User" user "User.Eco2")
		(25 "Edge.Cuts" user "Board Geometry/Outline")
		(27 "Margin" user)
		(31 "F.CrtYd" user "Package Geometry/Place Bound Top")
		(29 "B.CrtYd" user "Package Geometry/Place Bound Bottom")
		(35 "F.Fab" user "Ref Des/Assembly Top")
		(33 "B.Fab" user "Ref Des/Assembly Bottom")
	)
	(footprint ""
		(layer "F.Cu")
		(at 86.487 -72.39)
		(property "Reference" "C1063"
			(at 0 0 0)
			(layer "F.SilkS")
			(hide yes)
			(effects
				(font
					(size 1.27 1.27)
				)
			)
		)
		(property "Value" ""
			(at 0 0 0)
			(layer "F.Fab")
			(effects
				(font
					(size 1.27 1.27)
				)
			)
		)
		(duplicate_pad_numbers_are_jumpers no)
		(fp_line
			(start -0.7874 -0.4064)
			(end 0.7874 -0.4064)
			(stroke
				(width 0.1524)
				(type default)
			)
			(layer "F.SilkS")
		)
		(fp_line
			(start -0.7874 0.4064)
			(end -0.7874 -0.4064)
			(stroke
				(width 0.1524)
				(type default)
			)
			(layer "F.SilkS")
		)
		(fp_line
			(start 0.7874 -0.4064)
			(end 0.7874 0.4064)
			(stroke
				(width 0.1524)
				(type default)
			)
			(layer "F.SilkS")
		)
		(fp_line
			(start 0.7874 0.4064)
			(end -0.7874 0.4064)
			(stroke
				(width 0.1524)
				(type default)
			)
			(layer "F.SilkS")
		)
		(fp_line
			(start -0.67945 -0.305054)
			(end -0.12065 -0.305054)
			(stroke
				(width 0.1)
				(type default)
			)
			(layer "F.Fab")
		)
		(fp_line
			(start -0.67945 0.3048)
			(end -0.67945 -0.305054)
			(stroke
				(width 0.1)
				(type default)
			)
			(layer "F.Fab")
		)
		(fp_line
			(start -0.12065 -0.305054)
			(end -0.12065 -0.2794)
			(stroke
				(width 0.1)
				(type default)
			)
			(layer "F.Fab")
		)
		(fp_line
			(start -0.12065 -0.2794)
			(end 0.12065 -0.2794)
			(stroke
				(width 0.1)
				(type default)
			)
			(layer "F.Fab")
		)
		(fp_line
			(start -0.12065 0.2794)
			(end -0.12065 0.3048)
			(stroke
				(width 0.1)
				(type default)
			)
			(layer "F.Fab")
		)
		(fp_line
			(start -0.12065 0.3048)
			(end -0.67945 0.3048)
			(stroke
				(width 0.1)
				(type default)
			)
			(layer "F.Fab")
		)
		(fp_line
			(start 0.120396 0.2794)
			(end -0.12065 0.2794)
			(stroke
				(width 0.1)
				(type default)
			)
			(layer "F.Fab")
		)
		(fp_line
			(start 0.120396 0.3048)
			(end 0.120396 0.2794)
			(stroke
				(width 0.1)
				(type default)
			)
			(layer "F.Fab")
		)
		(fp_line
			(start 0.12065 -0.3048)
			(end 0.67945 -0.3048)
			(stroke
				(width 0.1)
				(type default)
			)
			(layer "F.Fab")
		)
		(fp_line
			(start 0.12065 -0.2794)
			(end 0.12065 -0.3048)
			(stroke
				(width 0.1)
				(type default)
			)
			(layer "F.Fab")
		)
		(fp_line
			(start 0.67945 -0.3048)
			(end 0.67945 0.3048)
			(stroke
				(width 0.1)
				(type default)
			)
			(layer "F.Fab")
		)
		(fp_line
			(start 0.67945 0.3048)
			(end 0.120396 0.3048)
			(stroke
				(width 0.1)
				(type default)
			)
			(layer "F.Fab")
		)
		(pad "1" smd circle
			(at -0.40005 0)
			(size 0 0)
			(layers "F.Cu" "F.Mask" "F.Paste")
			(net "P3V3_AUX")
		)
		(pad "2" smd circle
			(at 0.40005 0)
			(size 0 0)
			(layers "F.Cu" "F.Mask" "F.Paste")
			(net "GND")
		)
	)
	(footprint ""
		(layer "F.Cu")
		(at 273.35734 -122.880628 180)
		(property "Reference" "R4269"
			(at 0 0 180)
			(layer "F.SilkS")
			(hide yes)
			(effects
				(font
					(size 1.27 1.27)
				)
			)
		)
		(property "Value" ""
			(at 0 0 180)
			(layer "F.Fab")
			(effects
				(font
					(size 1.27 1.27)
				)
			)
		)
		(duplicate_pad_numbers_are_jumpers no)
		(fp_line
			(start 0.7874 0.4064)
			(end -0.7874 0.4064)
			(stroke
				(width 0.1524)
				(type default)
			)
			(layer "F.SilkS")
		)
		(fp_line
			(start 0.7874 -0.4064)
			(end 0.7874 0.4064)
			(stroke
				(width 0.1524)
				(type default)
			)
			(layer "F.SilkS")
		)
		(fp_line
			(start -0.7874 0.4064)
			(end -0.7874 -0.4064)
			(stroke
				(width 0.1524)
				(type default)
			)
			(layer "F.SilkS")
		)
		(fp_line
			(start -0.7874 -0.4064)
			(end 0.7874 -0.4064)
			(stroke
				(width 0.1524)
				(type default)
			)
			(layer "F.SilkS")
		)
		(fp_line
			(start 0.67945 0.3048)
			(end 0.120396 0.3048)
			(stroke
				(width 0.1)
				(type default)
			)
			(layer "F.Fab")
		)
		(fp_line
			(start 0.67945 -0.3048)
			(end 0.67945 0.3048)
			(stroke
				(width 0.1)
				(type default)
			)
			(layer "F.Fab")
		)
		(fp_line
			(start 0.12065 -0.2794)
			(end 0.12065 -0.3048)
			(stroke
				(width 0.1)
				(type default)
			)
			(layer "F.Fab")
		)
		(fp_line
			(start 0.12065 -0.3048)
			(end 0.67945 -0.3048)
			(stroke
				(width 0.1)
				(type default)
			)
			(layer "F.Fab")
		)
		(fp_line
			(start 0.120396 0.3048)
			(end 0.120396 0.2794)
			(stroke
				(width 0.1)
				(type default)
			)
			(layer "F.Fab")
		)
		(fp_line
			(start 0.120396 0.2794)
			(end -0.12065 0.2794)
			(stroke
				(width 0.1)
				(type default)
			)
			(layer "F.Fab")
		)
		(fp_line
			(start -0.12065 0.3048)
			(end -0.67945 0.3048)
			(stroke
				(width 0.1)
				(type default)
			)
			(layer "F.Fab")
		)
		(fp_line
			(start -0.12065 0.2794)
			(end -0.12065 0.3048)
			(stroke
				(width 0.1)
				(type default)
			)
			(layer "F.Fab")
		)
		(fp_line
			(start -0.12065 -0.2794)
			(end 0.12065 -0.2794)
			(stroke
				(width 0.1)
				(type default)
			)
			(layer "F.Fab")
		)
		(fp_line
			(start -0.12065 -0.305054)
			(end -0.12065 -0.2794)
			(stroke
				(width 0.1)
				(type default)
			)
			(layer "F.Fab")
		)
		(fp_line
			(start -0.67945 0.3048)
			(end -0.67945 -0.305054)
			(stroke
				(width 0.1)
				(type default)
			)
			(layer "F.Fab")
		)
		(fp_line
			(start -0.67945 -0.305054)
			(end -0.12065 -0.305054)
			(stroke
				(width 0.1)
				(type default)
			)
			(layer "F.Fab")
		)
		(pad "1" smd circle
			(at -0.40005 0 180)
			(size 0 0)
			(layers "F.Cu" "F.Mask" "F.Paste")
			(net "P3V3_AUX")
		)
		(pad "2" smd circle
			(at 0.40005 0 180)
			(size 0 0)
			(layers "F.Cu" "F.Mask" "F.Paste")
			(net "SMB_VR_SENSOR_3V3AUX_SCL")
		)
	)
)
